(kicad_pcb
	(version 20260206)
	(generator "pcbnew")
	(generator_version "10.0")
	(general
		(thickness 1.6)
		(legacy_teardrops no)
	)
	(paper "A4")
	(title_block
		(title "baseboard — 13948-1b.1110WZS1818.brd")
		(comment 1 "Honey Badger (Wiwynn) / footprints 2518-2523 of 2523")
	)
	(layers
		(0 "F.Cu" signal "TOP")
		(4 "In1.Cu" signal "L2GND")
		(6 "In2.Cu" signal "L3")
		(8 "In3.Cu" signal "L4VCC")
		(10 "In4.Cu" signal "L5VCC")
		(12 "In5.Cu" signal "L6")
		(14 "In6.Cu" signal "L7GND")
		(2 "B.Cu" signal "BOTTOM")
		(9 "F.Adhes" user "F.Adhesive")
		(11 "B.Adhes" user "B.Adhesive")
		(13 "F.Paste" user "Package Geometry/Pastemask Top")
		(15 "B.Paste" user "Package Geometry/Pastemask Bottom")
		(5 "F.SilkS" user "Ref Des/Silkscreen Top")
		(7 "B.SilkS" user "Ref Des/Silkscreen Bottom")
		(1 "F.Mask" user "Board Geometry/Soldermask Top")
		(3 "B.Mask" user "Board Geometry/Soldermask Bottom")
		(17 "Dwgs.User" user "User.Drawings")
		(19 "Cmts.User" user "User.Comments")
		(21 "Eco1.User" user "User.Eco1")
		(23 "Eco2.User" user "User.Eco2")
		(25 "Edge.Cuts" user "Board Geometry/Outline")
		(27 "Margin" user)
		(31 "F.CrtYd" user "Package Geometry/Place Bound Top")
		(29 "B.CrtYd" user "Package Geometry/Place Bound Bottom")
		(35 "F.Fab" user "Ref Des/Assembly Top")
		(33 "B.Fab" user "Ref Des/Assembly Bottom")
	)
	(footprint ""
		(layer "B.Cu")
		(at 110.748826 -41.8719 -90)
		(property "Reference" "SC989"
			(at 0 0 90)
			(layer "B.SilkS")
			(hide yes)
			(effects
				(font
					(size 1.27 1.27)
				)
				(justify mirror)
			)
		)
		(property "Value" "SCD1U16V2KX-3GP"
			(at -1.1811 -2.7051 270)
			(unlocked yes)
			(layer "B.Fab")
			(hide yes)
			(effects
				(font
					(size 1.016 1.016)
					(thickness 0.1524)
				)
				(justify mirror)
			)
		)
		(property "Device Type" "C402H22"
			(at -1.1811 -4.2291 270)
			(unlocked yes)
			(layer "B.Fab")
			(hide yes)
			(effects
				(font
					(size 1.016 1.016)
					(thickness 0.1524)
				)
				(justify mirror)
			)
		)
		(duplicate_pad_numbers_are_jumpers no)
		(fp_rect
			(start 0.4318 0.9525)
			(end -0.4318 -0.9525)
			(stroke
				(width 0)
				(type default)
			)
			(fill no)
			(layer "B.CrtYd")
		)
		(fp_rect
			(start 0.4318 0.9525)
			(end -0.4318 -0.9525)
			(stroke
				(width 0)
				(type default)
			)
			(fill no)
			(layer "B.Fab")
		)
		(pad "1" smd custom
			(at 0 -0.4445 90)
			(size 0.1524 0.1524)
			(layers "B.Cu" "B.Mask" "B.Paste")
			(net "P1V8_C")
			(options
				(clearance outline)
				(anchor circle)
			)
			(primitives
				(gr_poly
					(pts
						(arc
							(start 0.3048 0.2032)
							(mid 0.275042 0.275042)
							(end 0.2032 0.3048)
						)
						(arc
							(start -0.2032 0.3048)
							(mid -0.275042 0.275042)
							(end -0.3048 0.2032)
						)
						(arc
							(start -0.3048 -0.2032)
							(mid -0.275042 -0.275042)
							(end -0.2032 -0.3048)
						)
						(arc
							(start 0.2032 -0.3048)
							(mid 0.275042 -0.275042)
							(end 0.3048 -0.2032)
						)
					)
					(width 0)
					(fill yes)
				)
			)
		)
		(pad "2" smd custom
			(at 0 0.4445 90)
			(size 0.1524 0.1524)
			(layers "B.Cu" "B.Mask" "B.Paste")
			(net "GND")
			(options
				(clearance outline)
				(anchor circle)
			)
			(primitives
				(gr_poly
					(pts
						(arc
							(start 0.3048 0.2032)
							(mid 0.275042 0.275042)
							(end 0.2032 0.3048)
						)
						(arc
							(start -0.2032 0.3048)
							(mid -0.275042 0.275042)
							(end -0.3048 0.2032)
						)
						(arc
							(start -0.3048 -0.2032)
							(mid -0.275042 -0.275042)
							(end -0.2032 -0.3048)
						)
						(arc
							(start 0.2032 -0.3048)
							(mid 0.275042 -0.275042)
							(end 0.3048 -0.2032)
						)
					)
					(width 0)
					(fill yes)
				)
			)
		)
	)
	(footprint ""
		(layer "B.Cu")
		(at 294.33012 -170.28922)
		(property "Reference" "TP153"
			(at 0 0 0)
			(layer "B.SilkS")
			(hide yes)
			(effects
				(font
					(size 1.27 1.27)
				)
				(justify mirror)
			)
		)
		(property "Value" "TPAD28"
			(at -0.0127 -1.8034 0)
			(unlocked yes)
			(layer "B.Fab")
			(hide yes)
			(effects
				(font
					(size 1.016 1.016)
					(thickness 0.1524)
				)
				(justify mirror)
			)
		)
		(property "Device Type" "TPAD28"
			(at -0.0127 -3.3274 0)
			(unlocked yes)
			(layer "B.Fab")
			(hide yes)
			(effects
				(font
					(size 1.016 1.016)
					(thickness 0.1524)
				)
				(justify mirror)
			)
		)
		(duplicate_pad_numbers_are_jumpers no)
		(fp_poly
			(pts
				(arc
					(start 0.3556 0)
					(mid -0.3556 0)
					(end 0.3556 0)
				)
			)
			(stroke
				(width 0)
				(type default)
			)
			(fill no)
			(layer "B.CrtYd")
		)
		(fp_poly
			(pts
				(arc
					(start 0.6096 0)
					(mid -0.6096 0)
					(end 0.6096 0)
				)
			)
			(stroke
				(width 0)
				(type default)
			)
			(fill no)
			(layer "B.Fab")
		)
		(pad "1" smd circle
			(at 0 0 180)
			(size 0.7112 0.7112)
			(layers "B.Cu" "B.Mask" "B.Paste")
			(net "TP_BMC_GPIOU3")
		)
	)
	(footprint ""
		(layer "B.Cu")
		(at 128.79197 -104.267)
		(property "Reference" "SC1172"
			(at 0 0 0)
			(layer "B.SilkS")
			(hide yes)
			(effects
				(font
					(size 1.27 1.27)
				)
				(justify mirror)
			)
		)
		(property "Value" "SC1U10V2KX-4-GP"
			(at -1.1811 -2.7051 0)
			(unlocked yes)
			(layer "B.Fab")
			(hide yes)
			(effects
				(font
					(size 1.016 1.016)
					(thickness 0.1524)
				)
				(justify mirror)
			)
		)
		(property "Device Type" "C402H22"
			(at -1.1811 -4.2291 0)
			(unlocked yes)
			(layer "B.Fab")
			(hide yes)
			(effects
				(font
					(size 1.016 1.016)
					(thickness 0.1524)
				)
				(justify mirror)
			)
		)
		(duplicate_pad_numbers_are_jumpers no)
		(fp_rect
			(start 0.4318 0.9525)
			(end -0.4318 -0.9525)
			(stroke
				(width 0)
				(type default)
			)
			(fill no)
			(layer "B.CrtYd")
		)
		(fp_rect
			(start 0.4318 0.9525)
			(end -0.4318 -0.9525)
			(stroke
				(width 0)
				(type default)
			)
			(fill no)
			(layer "B.Fab")
		)
		(pad "1" smd custom
			(at 0 -0.4445 180)
			(size 0.1524 0.1524)
			(layers "B.Cu" "B.Mask" "B.Paste")
			(net "GB_VDDA")
			(options
				(clearance outline)
				(anchor circle)
			)
			(primitives
				(gr_poly
					(pts
						(arc
							(start 0.3048 0.2032)
							(mid 0.275042 0.275042)
							(end 0.2032 0.3048)
						)
						(arc
							(start -0.2032 0.3048)
							(mid -0.275042 0.275042)
							(end -0.3048 0.2032)
						)
						(arc
							(start -0.3048 -0.2032)
							(mid -0.275042 -0.275042)
							(end -0.2032 -0.3048)
						)
						(arc
							(start 0.2032 -0.3048)
							(mid 0.275042 -0.275042)
							(end 0.3048 -0.2032)
						)
					)
					(width 0)
					(fill yes)
				)
			)
		)
		(pad "2" smd custom
			(at 0 0.4445 180)
			(size 0.1524 0.1524)
			(layers "B.Cu" "B.Mask" "B.Paste")
			(net "GND")
			(options
				(clearance outline)
				(anchor circle)
			)
			(primitives
				(gr_poly
					(pts
						(arc
							(start 0.3048 0.2032)
							(mid 0.275042 0.275042)
							(end 0.2032 0.3048)
						)
						(arc
							(start -0.2032 0.3048)
							(mid -0.275042 0.275042)
							(end -0.3048 0.2032)
						)
						(arc
							(start -0.3048 -0.2032)
							(mid -0.275042 -0.275042)
							(end -0.2032 -0.3048)
						)
						(arc
							(start 0.2032 -0.3048)
							(mid 0.275042 -0.275042)
							(end 0.3048 -0.2032)
						)
					)
					(width 0)
					(fill yes)
				)
			)
		)
	)
	(footprint ""
		(layer "B.Cu")
		(at 319.405 -182.753 90)
		(property "Reference" "C8089"
			(at 0 0 90)
			(layer "B.SilkS")
			(hide yes)
			(effects
				(font
					(size 1.27 1.27)
				)
				(justify mirror)
			)
		)
		(property "Value" "SCD1U25V2KX-2-GP"
			(at -1.1811 -2.7051 90)
			(unlocked yes)
			(layer "B.Fab")
			(hide yes)
			(effects
				(font
					(size 1.016 1.016)
					(thickness 0.1524)
				)
				(justify mirror)
			)
		)
		(property "Device Type" "C402H22"
			(at -1.1811 -4.2291 90)
			(unlocked yes)
			(layer "B.Fab")
			(hide yes)
			(effects
				(font
					(size 1.016 1.016)
					(thickness 0.1524)
				)
				(justify mirror)
			)
		)
		(duplicate_pad_numbers_are_jumpers no)
		(fp_rect
			(start 0.4318 0.9525)
			(end -0.4318 -0.9525)
			(stroke
				(width 0)
				(type default)
			)
			(fill no)
			(layer "B.CrtYd")
		)
		(fp_rect
			(start 0.4318 0.9525)
			(end -0.4318 -0.9525)
			(stroke
				(width 0)
				(type default)
			)
			(fill no)
			(layer "B.Fab")
		)
		(pad "1" smd custom
			(at 0 -0.4445 270)
			(size 0.1524 0.1524)
			(layers "B.Cu" "B.Mask" "B.Paste")
			(net "ADC_P1V5_E")
			(options
				(clearance outline)
				(anchor circle)
			)
			(primitives
				(gr_poly
					(pts
						(arc
							(start 0.3048 0.2032)
							(mid 0.275042 0.275042)
							(end 0.2032 0.3048)
						)
						(arc
							(start -0.2032 0.3048)
							(mid -0.275042 0.275042)
							(end -0.3048 0.2032)
						)
						(arc
							(start -0.3048 -0.2032)
							(mid -0.275042 -0.275042)
							(end -0.2032 -0.3048)
						)
						(arc
							(start 0.2032 -0.3048)
							(mid 0.275042 -0.275042)
							(end 0.3048 -0.2032)
						)
					)
					(width 0)
					(fill yes)
				)
			)
		)
		(pad "2" smd custom
			(at 0 0.4445 270)
			(size 0.1524 0.1524)
			(layers "B.Cu" "B.Mask" "B.Paste")
			(net "GND")
			(options
				(clearance outline)
				(anchor circle)
			)
			(primitives
				(gr_poly
					(pts
						(arc
							(start 0.3048 0.2032)
							(mid 0.275042 0.275042)
							(end 0.2032 0.3048)
						)
						(arc
							(start -0.2032 0.3048)
							(mid -0.275042 0.275042)
							(end -0.3048 0.2032)
						)
						(arc
							(start -0.3048 -0.2032)
							(mid -0.275042 -0.275042)
							(end -0.2032 -0.3048)
						)
						(arc
							(start 0.2032 -0.3048)
							(mid 0.275042 -0.275042)
							(end 0.3048 -0.2032)
						)
					)
					(width 0)
					(fill yes)
				)
			)
		)
	)
	(footprint ""
		(layer "B.Cu")
		(at 171.704 -118.364 -90)
		(property "Reference" "PR150"
			(at 0 0 90)
			(layer "B.SilkS")
			(hide yes)
			(effects
				(font
					(size 1.27 1.27)
				)
				(justify mirror)
			)
		)
		(property "Value" "0R3J-0-U-GP"
			(at 0.0254 -2.5146 270)
			(unlocked yes)
			(layer "B.Fab")
			(hide yes)
			(effects
				(font
					(size 1.016 1.016)
					(thickness 0.1524)
				)
				(justify mirror)
			)
		)
		(property "Device Type" "R603H22"
			(at 0.0254 -4.0386 270)
			(unlocked yes)
			(layer "B.Fab")
			(hide yes)
			(effects
				(font
					(size 1.016 1.016)
					(thickness 0.1524)
				)
				(justify mirror)
			)
		)
		(duplicate_pad_numbers_are_jumpers no)
		(fp_line
			(start -0.2032 0)
			(end -0.4826 0)
			(stroke
				(width 0.2032)
				(type default)
			)
			(layer "B.SilkS")
		)
		(fp_line
			(start 0.4826 0)
			(end 0.2032 0)
			(stroke
				(width 0.2032)
				(type default)
			)
			(layer "B.SilkS")
		)
		(fp_rect
			(start 0.5842 1.3335)
			(end -0.5842 -1.3335)
			(stroke
				(width 0)
				(type default)
			)
			(fill no)
			(layer "B.CrtYd")
		)
		(fp_rect
			(start 0.5842 1.3335)
			(end -0.5842 -1.3335)
			(stroke
				(width 0)
				(type default)
			)
			(fill no)
			(layer "B.Fab")
		)
		(pad "1" smd custom
			(at 0 -0.762 90)
			(size 0.2159 0.2159)
			(layers "B.Cu" "B.Mask" "B.Paste")
			(net "P0V9_E_VIN")
			(options
				(clearance outline)
				(anchor circle)
			)
			(primitives
				(gr_poly
					(pts
						(arc
							(start -0.3302 0.4318)
							(mid -0.402042 0.402042)
							(end -0.4318 0.3302)
						)
						(arc
							(start -0.4318 -0.3302)
							(mid -0.402042 -0.402042)
							(end -0.3302 -0.4318)
						)
						(arc
							(start 0.3302 -0.4318)
							(mid 0.402042 -0.402042)
							(end 0.4318 -0.3302)
						)
						(arc
							(start 0.4318 0.3302)
							(mid 0.402042 0.402042)
							(end 0.3302 0.4318)
						)
					)
					(width 0)
					(fill yes)
				)
			)
		)
		(pad "2" smd custom
			(at 0 0.762 90)
			(size 0.2159 0.2159)
			(layers "B.Cu" "B.Mask" "B.Paste")
			(net "P0V9_E_VDD")
			(options
				(clearance outline)
				(anchor circle)
			)
			(primitives
				(gr_poly
					(pts
						(arc
							(start -0.3302 0.4318)
							(mid -0.402042 0.402042)
							(end -0.4318 0.3302)
						)
						(arc
							(start -0.4318 -0.3302)
							(mid -0.402042 -0.402042)
							(end -0.3302 -0.4318)
						)
						(arc
							(start 0.3302 -0.4318)
							(mid 0.402042 -0.402042)
							(end 0.4318 -0.3302)
						)
						(arc
							(start 0.4318 0.3302)
							(mid 0.402042 0.402042)
							(end 0.3302 0.4318)
						)
					)
					(width 0)
					(fill yes)
				)
			)
		)
	)
	(footprint ""
		(layer "B.Cu")
		(at 107.58297 -94.615 -90)
		(property "Reference" "SC1213"
			(at 0 0 90)
			(layer "B.SilkS")
			(hide yes)
			(effects
				(font
					(size 1.27 1.27)
				)
				(justify mirror)
			)
		)
		(property "Value" "SC1KP50V2KX-1GP"
			(at -1.1811 -2.7051 270)
			(unlocked yes)
			(layer "B.Fab")
			(hide yes)
			(effects
				(font
					(size 1.016 1.016)
					(thickness 0.1524)
				)
				(justify mirror)
			)
		)
		(property "Device Type" "C402H22"
			(at -1.1811 -4.2291 270)
			(unlocked yes)
			(layer "B.Fab")
			(hide yes)
			(effects
				(font
					(size 1.016 1.016)
					(thickness 0.1524)
				)
				(justify mirror)
			)
		)
		(duplicate_pad_numbers_are_jumpers no)
		(fp_rect
			(start 0.4318 0.9525)
			(end -0.4318 -0.9525)
			(stroke
				(width 0)
				(type default)
			)
			(fill no)
			(layer "B.CrtYd")
		)
		(fp_rect
			(start 0.4318 0.9525)
			(end -0.4318 -0.9525)
			(stroke
				(width 0)
				(type default)
			)
			(fill no)
			(layer "B.Fab")
		)
		(pad "1" smd custom
			(at 0 -0.4445 90)
			(size 0.1524 0.1524)
			(layers "B.Cu" "B.Mask" "B.Paste")
			(net "P1V8_E")
			(options
				(clearance outline)
				(anchor circle)
			)
			(primitives
				(gr_poly
					(pts
						(arc
							(start 0.3048 0.2032)
							(mid 0.275042 0.275042)
							(end 0.2032 0.3048)
						)
						(arc
							(start -0.2032 0.3048)
							(mid -0.275042 0.275042)
							(end -0.3048 0.2032)
						)
						(arc
							(start -0.3048 -0.2032)
							(mid -0.275042 -0.275042)
							(end -0.2032 -0.3048)
						)
						(arc
							(start 0.2032 -0.3048)
							(mid 0.275042 -0.275042)
							(end 0.3048 -0.2032)
						)
					)
					(width 0)
					(fill yes)
				)
			)
		)
		(pad "2" smd custom
			(at 0 0.4445 90)
			(size 0.1524 0.1524)
			(layers "B.Cu" "B.Mask" "B.Paste")
			(net "GND")
			(options
				(clearance outline)
				(anchor circle)
			)
			(primitives
				(gr_poly
					(pts
						(arc
							(start 0.3048 0.2032)
							(mid 0.275042 0.275042)
							(end 0.2032 0.3048)
						)
						(arc
							(start -0.2032 0.3048)
							(mid -0.275042 0.275042)
							(end -0.3048 0.2032)
						)
						(arc
							(start -0.3048 -0.2032)
							(mid -0.275042 -0.275042)
							(end -0.2032 -0.3048)
						)
						(arc
							(start 0.2032 -0.3048)
							(mid 0.275042 -0.275042)
							(end 0.3048 -0.2032)
						)
					)
					(width 0)
					(fill yes)
				)
			)
		)
	)
)
